# BASEBOARD_FAB2 (Tioga Pass) — schematic netlist excerpt (pin names and nets, part order shuffled) for the footprints in the layout excerpt that follows; sources: Cadence DE-HDL packaged netlist, KiCad conversion of Wiwynn_Tioga_Pass_MB.brd

C9U5  CAPP  470UF 2.5V 20% ALUM  pkg 3018  page 225 : A = PVDDQ_GHJ ; B = GND

(kicad_pcb
	(version 20260206)
	(generator "pcbnew")
	(generator_version "10.0")
	(general
		(thickness 1.6)
		(legacy_teardrops no)
	)
	(paper "A4")
	(title_block
		(title "Wiwynn_Tioga_Pass_MB.brd")
		(comment 1 "Tioga Pass / footprints 4561-4561 of 4770")
	)
	(layers
		(0 "F.Cu" signal "TOP")
		(4 "In1.Cu" signal "L2GND")
		(6 "In2.Cu" signal "L3")
		(8 "In3.Cu" signal "L4GND")
		(10 "In4.Cu" signal "L5")
		(12 "In5.Cu" signal "L6GND")
		(14 "In6.Cu" signal "L7VCC")
		(16 "In7.Cu" signal "L8VCC")
		(18 "In8.Cu" signal "L9GND")
		(20 "In9.Cu" signal "L10")
		(22 "In10.Cu" signal "L11GND")
		(24 "In11.Cu" signal "L12")
		(26 "In12.Cu" signal "L13GND")
		(2 "B.Cu" signal "BOTTOM")
		(9 "F.Adhes" user "F.Adhesive")
		(11 "B.Adhes" user "B.Adhesive")
		(13 "F.Paste" user "Package Geometry/Pastemask Top")
		(15 "B.Paste" user "Package Geometry/Pastemask Bottom")
		(5 "F.SilkS" user "Ref Des/Silkscreen Top")
		(7 "B.SilkS" user "Ref Des/Silkscreen Bottom")
		(1 "F.Mask" user "Board Geometry/Soldermask Top")
		(3 "B.Mask" user "Board Geometry/Soldermask Bottom")
		(17 "Dwgs.User" user "User.Drawings")
		(19 "Cmts.User" user "User.Comments")
		(21 "Eco1.User" user "User.Eco1")
		(23 "Eco2.User" user "User.Eco2")
		(25 "Edge.Cuts" user "Board Geometry/Outline")
		(27 "Margin" user)
		(31 "F.CrtYd" user "Package Geometry/Place Bound Top")
		(29 "B.CrtYd" user "Package Geometry/Place Bound Bottom")
		(35 "F.Fab" user "Ref Des/Assembly Top")
		(33 "B.Fab" user "Ref Des/Assembly Bottom")
	)
	(footprint ""
		(layer "B.Cu")
		(at 17.9832 -8.9662 -90)
		(property "Reference" "C9U5"
			(at -2.00533 9.271 0)
			(unlocked yes)
			(layer "B.SilkS")
			(effects
				(font
					(size 0.7874 0.5842)
					(thickness 0.1524)
				)
				(justify mirror)
			)
		)
		(property "Value" ""
			(at 0 0 90)
			(layer "B.Fab")
			(effects
				(font
					(size 1.27 1.27)
				)
				(justify mirror)
			)
		)
		(duplicate_pad_numbers_are_jumpers no)
		(fp_line
			(start -2.286 7.366)
			(end -1.600708 7.366)
			(stroke
				(width 0.1524)
				(type default)
			)
			(layer "B.SilkS")
		)
		(fp_line
			(start -2.286 7.366)
			(end -2.286 1.63195)
			(stroke
				(width 0.1524)
				(type default)
			)
			(layer "B.SilkS")
		)
		(fp_line
			(start 2.286 7.366)
			(end 1.60147 7.366)
			(stroke
				(width 0.1524)
				(type default)
			)
			(layer "B.SilkS")
		)
		(fp_line
			(start 2.286 7.366)
			(end 2.286 1.632712)
			(stroke
				(width 0.1524)
				(type default)
			)
			(layer "B.SilkS")
		)
		(fp_line
			(start -2.504948 1.633728)
			(end -1.6002 1.633728)
			(stroke
				(width 0.1524)
				(type default)
			)
			(layer "B.SilkS")
		)
		(fp_line
			(start 2.563114 1.633728)
			(end 1.6002 1.633728)
			(stroke
				(width 0.1524)
				(type default)
			)
			(layer "B.SilkS")
		)
		(fp_line
			(start -2.504948 -1.616456)
			(end -2.504948 1.633728)
			(stroke
				(width 0.1524)
				(type default)
			)
			(layer "B.SilkS")
		)
		(fp_line
			(start -1.6002 -1.616456)
			(end -2.504948 -1.616456)
			(stroke
				(width 0.1524)
				(type default)
			)
			(layer "B.SilkS")
		)
		(fp_line
			(start 1.6002 -1.616456)
			(end 2.563114 -1.616456)
			(stroke
				(width 0.1524)
				(type default)
			)
			(layer "B.SilkS")
		)
		(fp_line
			(start 2.563114 -1.616456)
			(end 2.563114 1.633728)
			(stroke
				(width 0.1524)
				(type default)
			)
			(layer "B.SilkS")
		)
		(fp_rect
			(start 2.286 -0.254)
			(end -2.286 7.366)
			(stroke
				(width 0)
				(type default)
			)
			(fill no)
			(layer "B.CrtYd")
		)
		(fp_line
			(start -2.286 7.366)
			(end 2.286 7.366)
			(stroke
				(width 0.1)
				(type default)
			)
			(layer "B.Fab")
		)
		(fp_line
			(start 2.286 7.366)
			(end 2.286 -0.254)
			(stroke
				(width 0.1)
				(type default)
			)
			(layer "B.Fab")
		)
		(fp_line
			(start -2.286 -0.254)
			(end -2.286 7.366)
			(stroke
				(width 0.1)
				(type default)
			)
			(layer "B.Fab")
		)
		(fp_line
			(start 2.286 -0.254)
			(end -2.286 -0.254)
			(stroke
				(width 0.1)
				(type default)
			)
			(layer "B.Fab")
		)
		(pad "1" smd rect
			(at 0 0 90)
			(size 2.54 3.048)
			(layers "B.Cu" "B.Mask" "B.Paste")
			(net "PVDDQ_GHJ")
		)
		(pad "2" smd rect
			(at 0 7.112 90)
			(size 2.54 3.048)
			(layers "B.Cu" "B.Mask" "B.Paste")
			(net "GND")
		)
	)
)
